# T6G (Grand Teton) — schematic netlist excerpt (pin names and nets, part order shuffled) for the footprints in the layout excerpt that follows; sources: Cadence DE-HDL packaged netlist, KiCad conversion of 04192023_DAF0TMB3IC0_F0TG_MB_C_brd_V02_OCP.brd

PR74  Q_RES  0 5% CHIP  pkg 0402LF  page 200 : A = P12V_AUX ; B = PVDDCR_CPU1_P0_VINSEN
D98  Q_LED  IC  pkg SMLF  page 254 : A = LED_P5V ; C = GND
C900  Q_CAP_DIFFBUS  DIFF BUS_0.22UF 6.3V 20% X6S  pkg C0201  page 64 : \1\ = P5E_CPU0_P3_TX_C_DN<0> ; \2\ = P5E_CPU0_P3_TX_DN<0>

(kicad_pcb
	(version 20260206)
	(generator "pcbnew")
	(generator_version "10.0")
	(general
		(thickness 1.6)
		(legacy_teardrops no)
	)
	(paper "A4")
	(title_block
		(title "04192023_DAF0TMB3IC0_F0TG_MB_C_brd_V02_OCP.brd")
		(comment 1 "Grand Teton / footprints 1651-1653 of 8354")
	)
	(layers
		(0 "F.Cu" signal "TOP")
		(4 "In1.Cu" signal "GND")
		(6 "In2.Cu" signal "IN1")
		(8 "In3.Cu" signal "GND1")
		(10 "In4.Cu" signal "IN2")
		(12 "In5.Cu" signal "GND2")
		(14 "In6.Cu" signal "IN3")
		(16 "In7.Cu" signal "GND3")
		(18 "In8.Cu" signal "VCC")
		(20 "In9.Cu" signal "VCC1")
		(22 "In10.Cu" signal "GND4")
		(24 "In11.Cu" signal "IN4")
		(26 "In12.Cu" signal "GND5")
		(28 "In13.Cu" signal "IN5")
		(30 "In14.Cu" signal "GND6")
		(32 "In15.Cu" signal "IN6")
		(34 "In16.Cu" signal "GND7")
		(2 "B.Cu" signal "BOTTOM")
		(9 "F.Adhes" user "F.Adhesive")
		(11 "B.Adhes" user "B.Adhesive")
		(13 "F.Paste" user "Package Geometry/Pastemask Top")
		(15 "B.Paste" user "Package Geometry/Pastemask Bottom")
		(5 "F.SilkS" user "Ref Des/Silkscreen Top")
		(7 "B.SilkS" user "Ref Des/Silkscreen Bottom")
		(1 "F.Mask" user "Board Geometry/Soldermask Top")
		(3 "B.Mask" user "Board Geometry/Soldermask Bottom")
		(17 "Dwgs.User" user "User.Drawings")
		(19 "Cmts.User" user "User.Comments")
		(21 "Eco1.User" user "User.Eco1")
		(23 "Eco2.User" user "User.Eco2")
		(25 "Edge.Cuts" user "Board Geometry/Outline")
		(27 "Margin" user)
		(31 "F.CrtYd" user "Package Geometry/Place Bound Top")
		(29 "B.CrtYd" user "Package Geometry/Place Bound Bottom")
		(35 "F.Fab" user "Ref Des/Assembly Top")
		(33 "B.Fab" user "Ref Des/Assembly Bottom")
	)
	(footprint ""
		(layer "F.Cu")
		(at 314.475876 -70.098412 90)
		(property "Reference" "D98"
			(at -3.934714 -0.691642 90)
			(unlocked yes)
			(layer "F.SilkS")
			(effects
				(font
					(size 0.7874 0.5842)
					(thickness 0.1524)
				)
				(justify left)
			)
		)
		(property "Value" ""
			(at 0 0 90)
			(layer "F.Fab")
			(effects
				(font
					(size 1.27 1.27)
				)
			)
		)
		(duplicate_pad_numbers_are_jumpers no)
		(fp_line
			(start 1.16078 -0.4826)
			(end 1.16078 0.4826)
			(stroke
				(width 0.1524)
				(type default)
			)
			(layer "F.SilkS")
		)
		(fp_line
			(start 1.03378 -0.4826)
			(end 1.03378 0.4826)
			(stroke
				(width 0.1524)
				(type default)
			)
			(layer "F.SilkS")
		)
		(fp_line
			(start 0.90678 -0.4826)
			(end 0.90678 0.4826)
			(stroke
				(width 0.1524)
				(type default)
			)
			(layer "F.SilkS")
		)
		(fp_line
			(start -0.64008 -0.4826)
			(end 1.16078 -0.4826)
			(stroke
				(width 0.1524)
				(type default)
			)
			(layer "F.SilkS")
		)
		(fp_line
			(start -0.79248 -0.4826)
			(end 1.03378 -0.4826)
			(stroke
				(width 0.1524)
				(type default)
			)
			(layer "F.SilkS")
		)
		(fp_line
			(start -0.89408 -0.4826)
			(end 0.90678 -0.4826)
			(stroke
				(width 0.1524)
				(type default)
			)
			(layer "F.SilkS")
		)
		(fp_line
			(start 1.16078 0.4826)
			(end -0.64008 0.4826)
			(stroke
				(width 0.1524)
				(type default)
			)
			(layer "F.SilkS")
		)
		(fp_line
			(start 1.03378 0.4826)
			(end -0.79248 0.4826)
			(stroke
				(width 0.1524)
				(type default)
			)
			(layer "F.SilkS")
		)
		(fp_line
			(start 0.90678 0.4826)
			(end -0.90678 0.4826)
			(stroke
				(width 0.1524)
				(type default)
			)
			(layer "F.SilkS")
		)
		(fp_line
			(start -0.90678 0.4826)
			(end -0.90678 -0.4699)
			(stroke
				(width 0.1524)
				(type default)
			)
			(layer "F.SilkS")
		)
		(fp_line
			(start 0.499872 -0.249936)
			(end 0.499872 0.249936)
			(stroke
				(width 0.1)
				(type default)
			)
			(layer "F.Fab")
		)
		(fp_line
			(start -0.499872 -0.249936)
			(end 0.499872 -0.249936)
			(stroke
				(width 0.1)
				(type default)
			)
			(layer "F.Fab")
		)
		(fp_line
			(start 0.499872 0.249936)
			(end -0.499872 0.249936)
			(stroke
				(width 0.1)
				(type default)
			)
			(layer "F.Fab")
		)
		(fp_line
			(start -0.499872 0.249936)
			(end -0.499872 -0.249936)
			(stroke
				(width 0.1)
				(type default)
			)
			(layer "F.Fab")
		)
		(pad "A" smd rect
			(at -0.47498 0 90)
			(size 0.6096 0.7112)
			(layers "F.Cu" "F.Mask" "F.Paste")
			(net "LED_P5V")
		)
		(pad "C" smd rect
			(at 0.47498 0 90)
			(size 0.6096 0.7112)
			(layers "F.Cu" "F.Mask" "F.Paste")
			(net "GND")
		)
	)
	(footprint ""
		(layer "F.Cu")
		(at 318.262 -362.839 -90)
		(property "Reference" "PR74"
			(at 0 0 270)
			(layer "F.SilkS")
			(hide yes)
			(effects
				(font
					(size 1.27 1.27)
				)
			)
		)
		(property "Value" ""
			(at 0 0 270)
			(layer "F.Fab")
			(effects
				(font
					(size 1.27 1.27)
				)
			)
		)
		(duplicate_pad_numbers_are_jumpers no)
		(fp_line
			(start -0.7874 0.4064)
			(end -0.7874 -0.4064)
			(stroke
				(width 0.1524)
				(type default)
			)
			(layer "F.SilkS")
		)
		(fp_line
			(start 0.7874 0.4064)
			(end -0.7874 0.4064)
			(stroke
				(width 0.1524)
				(type default)
			)
			(layer "F.SilkS")
		)
		(fp_line
			(start -0.7874 -0.4064)
			(end 0.7874 -0.4064)
			(stroke
				(width 0.1524)
				(type default)
			)
			(layer "F.SilkS")
		)
		(fp_line
			(start 0.7874 -0.4064)
			(end 0.7874 0.4064)
			(stroke
				(width 0.1524)
				(type default)
			)
			(layer "F.SilkS")
		)
		(fp_line
			(start -0.67945 0.3048)
			(end -0.67945 -0.305054)
			(stroke
				(width 0.1)
				(type default)
			)
			(layer "F.Fab")
		)
		(fp_line
			(start -0.12065 0.3048)
			(end -0.67945 0.3048)
			(stroke
				(width 0.1)
				(type default)
			)
			(layer "F.Fab")
		)
		(fp_line
			(start 0.120396 0.3048)
			(end 0.120396 0.2794)
			(stroke
				(width 0.1)
				(type default)
			)
			(layer "F.Fab")
		)
		(fp_line
			(start 0.67945 0.3048)
			(end 0.120396 0.3048)
			(stroke
				(width 0.1)
				(type default)
			)
			(layer "F.Fab")
		)
		(fp_line
			(start -0.12065 0.2794)
			(end -0.12065 0.3048)
			(stroke
				(width 0.1)
				(type default)
			)
			(layer "F.Fab")
		)
		(fp_line
			(start 0.120396 0.2794)
			(end -0.12065 0.2794)
			(stroke
				(width 0.1)
				(type default)
			)
			(layer "F.Fab")
		)
		(fp_line
			(start -0.12065 -0.2794)
			(end 0.12065 -0.2794)
			(stroke
				(width 0.1)
				(type default)
			)
			(layer "F.Fab")
		)
		(fp_line
			(start 0.12065 -0.2794)
			(end 0.12065 -0.3048)
			(stroke
				(width 0.1)
				(type default)
			)
			(layer "F.Fab")
		)
		(fp_line
			(start 0.12065 -0.3048)
			(end 0.67945 -0.3048)
			(stroke
				(width 0.1)
				(type default)
			)
			(layer "F.Fab")
		)
		(fp_line
			(start 0.67945 -0.3048)
			(end 0.67945 0.3048)
			(stroke
				(width 0.1)
				(type default)
			)
			(layer "F.Fab")
		)
		(fp_line
			(start -0.67945 -0.305054)
			(end -0.12065 -0.305054)
			(stroke
				(width 0.1)
				(type default)
			)
			(layer "F.Fab")
		)
		(fp_line
			(start -0.12065 -0.305054)
			(end -0.12065 -0.2794)
			(stroke
				(width 0.1)
				(type default)
			)
			(layer "F.Fab")
		)
		(pad "1" smd circle
			(at -0.40005 0 270)
			(size 0 0)
			(layers "F.Cu" "F.Mask" "F.Paste")
			(net "P12V_AUX")
		)
		(pad "2" smd circle
			(at 0.40005 0 270)
			(size 0 0)
			(layers "F.Cu" "F.Mask" "F.Paste")
			(net "PVDDCR_CPU1_P0_VINSEN")
		)
	)
	(footprint ""
		(layer "F.Cu")
		(at 366.06734 -389.86206 180)
		(property "Reference" "C900"
			(at 0 0 180)
			(layer "F.SilkS")
			(hide yes)
			(effects
				(font
					(size 1.27 1.27)
				)
			)
		)
		(property "Value" ""
			(at 0 0 180)
			(layer "F.Fab")
			(effects
				(font
					(size 1.27 1.27)
				)
			)
		)
		(duplicate_pad_numbers_are_jumpers no)
		(fp_line
			(start 0.299974 0.150114)
			(end -0.299974 0.150114)
			(stroke
				(width 0.1)
				(type default)
			)
			(layer "F.Fab")
		)
		(fp_line
			(start 0.299974 -0.150114)
			(end 0.299974 0.150114)
			(stroke
				(width 0.1)
				(type default)
			)
			(layer "F.Fab")
		)
		(fp_line
			(start -0.299974 0.150114)
			(end -0.299974 -0.150114)
			(stroke
				(width 0.1)
				(type default)
			)
			(layer "F.Fab")
		)
		(fp_line
			(start -0.299974 -0.150114)
			(end 0.299974 -0.150114)
			(stroke
				(width 0.1)
				(type default)
			)
			(layer "F.Fab")
		)
		(pad "1" smd rect
			(at -0.2667 0 180)
			(size 0.3048 0.381)
			(layers "F.Cu" "F.Mask" "F.Paste")
			(net "P5E_CPU0_P3_TX_C_DN<0>")
		)
		(pad "2" smd rect
			(at 0.2667 0 180)
			(size 0.3048 0.381)
			(layers "F.Cu" "F.Mask" "F.Paste")
			(net "P5E_CPU0_P3_TX_DN<0>")
		)
	)
)
